(kicad_pcb
	(version 20260206)
	(generator "pcbnew")
	(generator_version "10.0")
	(general
		(thickness 1.6)
		(legacy_teardrops no)
	)
	(paper "A4")
	(title_block
		(title "dpb — 14545-sa.0730WZS0815.brd")
		(comment 1 "Honey Badger (Wiwynn) / footprints 895-902 of 1066")
	)
	(layers
		(0 "F.Cu" signal "TOP")
		(4 "In1.Cu" signal "L2GND")
		(6 "In2.Cu" signal "L3")
		(8 "In3.Cu" signal "L4VCC")
		(10 "In4.Cu" signal "L5VCC")
		(12 "In5.Cu" signal "L6")
		(14 "In6.Cu" signal "L7GND")
		(2 "B.Cu" signal "BOTTOM")
		(9 "F.Adhes" user "F.Adhesive")
		(11 "B.Adhes" user "B.Adhesive")
		(13 "F.Paste" user "Package Geometry/Pastemask Top")
		(15 "B.Paste" user "Package Geometry/Pastemask Bottom")
		(5 "F.SilkS" user "Ref Des/Silkscreen Top")
		(7 "B.SilkS" user "Ref Des/Silkscreen Bottom")
		(1 "F.Mask" user "Board Geometry/Soldermask Top")
		(3 "B.Mask" user "Board Geometry/Soldermask Bottom")
		(17 "Dwgs.User" user "User.Drawings")
		(19 "Cmts.User" user "User.Comments")
		(21 "Eco1.User" user "User.Eco1")
		(23 "Eco2.User" user "User.Eco2")
		(25 "Edge.Cuts" user "Board Geometry/Outline")
		(27 "Margin" user)
		(31 "F.CrtYd" user "Package Geometry/Place Bound Top")
		(29 "B.CrtYd" user "Package Geometry/Place Bound Bottom")
		(35 "F.Fab" user "Ref Des/Assembly Top")
		(33 "B.Fab" user "Ref Des/Assembly Bottom")
	)
	(footprint ""
		(layer "F.Cu")
		(at 46.2534 -236.6264 90)
		(property "Reference" "R401"
			(at 0 0 90)
			(layer "F.SilkS")
			(hide yes)
			(effects
				(font
					(size 1.27 1.27)
				)
			)
		)
		(property "Value" "10KR2F-2-GP"
			(at 0.064008 -3.993896 90)
			(unlocked yes)
			(layer "F.Fab")
			(hide yes)
			(effects
				(font
					(size 1.016 1.016)
					(thickness 0.1524)
				)
			)
		)
		(property "Device Type" "R402H16"
			(at 0.064008 -5.517896 90)
			(unlocked yes)
			(layer "F.Fab")
			(hide yes)
			(effects
				(font
					(size 1.016 1.016)
					(thickness 0.1524)
				)
			)
		)
		(duplicate_pad_numbers_are_jumpers no)
		(fp_line
			(start 0.508 -0.9398)
			(end -0.508 -0.9398)
			(stroke
				(width 0.1524)
				(type default)
			)
			(layer "F.SilkS")
		)
		(fp_line
			(start -0.508 -0.9398)
			(end -0.508 0.9398)
			(stroke
				(width 0.1524)
				(type default)
			)
			(layer "F.SilkS")
		)
		(fp_rect
			(start -0.508 0.9398)
			(end 0.508 -0.9398)
			(stroke
				(width 0)
				(type default)
			)
			(fill no)
			(layer "F.CrtYd")
		)
		(fp_rect
			(start -0.508 0.9398)
			(end 0.508 -0.9398)
			(stroke
				(width 0)
				(type default)
			)
			(fill no)
			(layer "F.Fab")
		)
		(pad "1" smd custom
			(at 0 -0.4445 90)
			(size 0.1397 0.1397)
			(layers "F.Cu" "F.Mask" "F.Paste")
			(net "P12V")
			(options
				(clearance outline)
				(anchor circle)
			)
			(primitives
				(gr_poly
					(pts
						(arc
							(start -0.1778 -0.2794)
							(mid -0.249642 -0.249642)
							(end -0.2794 -0.1778)
						)
						(arc
							(start -0.2794 0.1778)
							(mid -0.249642 0.249642)
							(end -0.1778 0.2794)
						)
						(arc
							(start 0.1778 0.2794)
							(mid 0.249642 0.249642)
							(end 0.2794 0.1778)
						)
						(arc
							(start 0.2794 -0.1778)
							(mid 0.249642 -0.249642)
							(end 0.1778 -0.2794)
						)
					)
					(width 0)
					(fill yes)
				)
			)
		)
		(pad "2" smd custom
			(at 0 0.4445 90)
			(size 0.1397 0.1397)
			(layers "F.Cu" "F.Mask" "F.Paste")
			(net "HDD12_LED_G")
			(options
				(clearance outline)
				(anchor circle)
			)
			(primitives
				(gr_poly
					(pts
						(arc
							(start -0.1778 -0.2794)
							(mid -0.249642 -0.249642)
							(end -0.2794 -0.1778)
						)
						(arc
							(start -0.2794 0.1778)
							(mid -0.249642 0.249642)
							(end -0.1778 0.2794)
						)
						(arc
							(start 0.1778 0.2794)
							(mid 0.249642 0.249642)
							(end 0.2794 0.1778)
						)
						(arc
							(start 0.2794 -0.1778)
							(mid 0.249642 -0.249642)
							(end 0.1778 -0.2794)
						)
					)
					(width 0)
					(fill yes)
				)
			)
		)
	)
	(footprint ""
		(layer "F.Cu")
		(at 8.381746 -156.4767 90)
		(property "Reference" "R359"
			(at 0 0 90)
			(layer "F.SilkS")
			(hide yes)
			(effects
				(font
					(size 1.27 1.27)
				)
			)
		)
		(property "Value" "10KR2F-2-GP"
			(at 0.064008 -3.993896 90)
			(unlocked yes)
			(layer "F.Fab")
			(hide yes)
			(effects
				(font
					(size 1.016 1.016)
					(thickness 0.1524)
				)
			)
		)
		(property "Device Type" "R402H16"
			(at 0.064008 -5.517896 90)
			(unlocked yes)
			(layer "F.Fab")
			(hide yes)
			(effects
				(font
					(size 1.016 1.016)
					(thickness 0.1524)
				)
			)
		)
		(duplicate_pad_numbers_are_jumpers no)
		(fp_line
			(start 0.508 -0.9398)
			(end -0.508 -0.9398)
			(stroke
				(width 0.1524)
				(type default)
			)
			(layer "F.SilkS")
		)
		(fp_line
			(start -0.508 -0.9398)
			(end -0.508 0.9398)
			(stroke
				(width 0.1524)
				(type default)
			)
			(layer "F.SilkS")
		)
		(fp_rect
			(start -0.508 0.9398)
			(end 0.508 -0.9398)
			(stroke
				(width 0)
				(type default)
			)
			(fill no)
			(layer "F.CrtYd")
		)
		(fp_rect
			(start -0.508 0.9398)
			(end 0.508 -0.9398)
			(stroke
				(width 0)
				(type default)
			)
			(fill no)
			(layer "F.Fab")
		)
		(pad "1" smd custom
			(at 0 -0.4445 90)
			(size 0.1397 0.1397)
			(layers "F.Cu" "F.Mask" "F.Paste")
			(net "TEMP_SENSOR_B_ADDR0&ID")
			(options
				(clearance outline)
				(anchor circle)
			)
			(primitives
				(gr_poly
					(pts
						(arc
							(start -0.1778 -0.2794)
							(mid -0.249642 -0.249642)
							(end -0.2794 -0.1778)
						)
						(arc
							(start -0.2794 0.1778)
							(mid -0.249642 0.249642)
							(end -0.1778 0.2794)
						)
						(arc
							(start 0.1778 0.2794)
							(mid 0.249642 0.249642)
							(end 0.2794 0.1778)
						)
						(arc
							(start 0.2794 -0.1778)
							(mid 0.249642 -0.249642)
							(end 0.1778 -0.2794)
						)
					)
					(width 0)
					(fill yes)
				)
			)
		)
		(pad "2" smd custom
			(at 0 0.4445 90)
			(size 0.1397 0.1397)
			(layers "F.Cu" "F.Mask" "F.Paste")
			(net "GND")
			(options
				(clearance outline)
				(anchor circle)
			)
			(primitives
				(gr_poly
					(pts
						(arc
							(start -0.1778 -0.2794)
							(mid -0.249642 -0.249642)
							(end -0.2794 -0.1778)
						)
						(arc
							(start -0.2794 0.1778)
							(mid -0.249642 0.249642)
							(end -0.1778 0.2794)
						)
						(arc
							(start 0.1778 0.2794)
							(mid 0.249642 0.249642)
							(end 0.2794 0.1778)
						)
						(arc
							(start 0.2794 -0.1778)
							(mid 0.249642 -0.249642)
							(end 0.1778 -0.2794)
						)
					)
					(width 0)
					(fill yes)
				)
			)
		)
	)
	(footprint ""
		(layer "F.Cu")
		(at 191.256412 -83.546696 -90)
		(property "Reference" "R169"
			(at 0 0 270)
			(layer "F.SilkS")
			(hide yes)
			(effects
				(font
					(size 1.27 1.27)
				)
			)
		)
		(property "Value" "0R2J-2-GP"
			(at 0.064008 -3.993896 270)
			(unlocked yes)
			(layer "F.Fab")
			(hide yes)
			(effects
				(font
					(size 1.016 1.016)
					(thickness 0.1524)
				)
			)
		)
		(property "Device Type" "R402H16"
			(at 0.064008 -5.517896 270)
			(unlocked yes)
			(layer "F.Fab")
			(hide yes)
			(effects
				(font
					(size 1.016 1.016)
					(thickness 0.1524)
				)
			)
		)
		(duplicate_pad_numbers_are_jumpers no)
		(fp_line
			(start -0.508 -0.9398)
			(end -0.508 0.9398)
			(stroke
				(width 0.1524)
				(type default)
			)
			(layer "F.SilkS")
		)
		(fp_line
			(start 0.508 -0.9398)
			(end -0.508 -0.9398)
			(stroke
				(width 0.1524)
				(type default)
			)
			(layer "F.SilkS")
		)
		(fp_rect
			(start -0.508 0.9398)
			(end 0.508 -0.9398)
			(stroke
				(width 0)
				(type default)
			)
			(fill no)
			(layer "F.CrtYd")
		)
		(fp_rect
			(start -0.508 0.9398)
			(end 0.508 -0.9398)
			(stroke
				(width 0)
				(type default)
			)
			(fill no)
			(layer "F.Fab")
		)
		(pad "1" smd custom
			(at 0 -0.4445 270)
			(size 0.1397 0.1397)
			(layers "F.Cu" "F.Mask" "F.Paste")
			(net "DRIVE_PWR4")
			(options
				(clearance outline)
				(anchor circle)
			)
			(primitives
				(gr_poly
					(pts
						(arc
							(start -0.1778 -0.2794)
							(mid -0.249642 -0.249642)
							(end -0.2794 -0.1778)
						)
						(arc
							(start -0.2794 0.1778)
							(mid -0.249642 0.249642)
							(end -0.1778 0.2794)
						)
						(arc
							(start 0.1778 0.2794)
							(mid 0.249642 0.249642)
							(end 0.2794 0.1778)
						)
						(arc
							(start 0.2794 -0.1778)
							(mid 0.249642 -0.249642)
							(end 0.1778 -0.2794)
						)
					)
					(width 0)
					(fill yes)
				)
			)
		)
		(pad "2" smd custom
			(at 0 0.4445 270)
			(size 0.1397 0.1397)
			(layers "F.Cu" "F.Mask" "F.Paste")
			(net "SW_PWR_HDD4")
			(options
				(clearance outline)
				(anchor circle)
			)
			(primitives
				(gr_poly
					(pts
						(arc
							(start -0.1778 -0.2794)
							(mid -0.249642 -0.249642)
							(end -0.2794 -0.1778)
						)
						(arc
							(start -0.2794 0.1778)
							(mid -0.249642 0.249642)
							(end -0.1778 0.2794)
						)
						(arc
							(start 0.1778 0.2794)
							(mid 0.249642 0.249642)
							(end 0.2794 0.1778)
						)
						(arc
							(start 0.2794 -0.1778)
							(mid 0.249642 -0.249642)
							(end 0.1778 -0.2794)
						)
					)
					(width 0)
					(fill yes)
				)
			)
		)
	)
	(footprint ""
		(layer "F.Cu")
		(at 209.422746 -452.6407 180)
		(property "Reference" "R329"
			(at 0 0 180)
			(layer "F.SilkS")
			(hide yes)
			(effects
				(font
					(size 1.27 1.27)
				)
			)
		)
		(property "Value" "4K7R2J-2-GP"
			(at 0.064008 -3.993896 180)
			(unlocked yes)
			(layer "F.Fab")
			(hide yes)
			(effects
				(font
					(size 1.016 1.016)
					(thickness 0.1524)
				)
			)
		)
		(property "Device Type" "R402H16"
			(at 0.064008 -5.517896 180)
			(unlocked yes)
			(layer "F.Fab")
			(hide yes)
			(effects
				(font
					(size 1.016 1.016)
					(thickness 0.1524)
				)
			)
		)
		(duplicate_pad_numbers_are_jumpers no)
		(fp_line
			(start 0.508 -0.9398)
			(end -0.508 -0.9398)
			(stroke
				(width 0.1524)
				(type default)
			)
			(layer "F.SilkS")
		)
		(fp_line
			(start -0.508 -0.9398)
			(end -0.508 0.9398)
			(stroke
				(width 0.1524)
				(type default)
			)
			(layer "F.SilkS")
		)
		(fp_rect
			(start -0.508 0.9398)
			(end 0.508 -0.9398)
			(stroke
				(width 0)
				(type default)
			)
			(fill no)
			(layer "F.CrtYd")
		)
		(fp_rect
			(start -0.508 0.9398)
			(end 0.508 -0.9398)
			(stroke
				(width 0)
				(type default)
			)
			(fill no)
			(layer "F.Fab")
		)
		(pad "1" smd custom
			(at 0 -0.4445 180)
			(size 0.1397 0.1397)
			(layers "F.Cu" "F.Mask" "F.Paste")
			(net "P3V3")
			(options
				(clearance outline)
				(anchor circle)
			)
			(primitives
				(gr_poly
					(pts
						(arc
							(start -0.1778 -0.2794)
							(mid -0.249642 -0.249642)
							(end -0.2794 -0.1778)
						)
						(arc
							(start -0.2794 0.1778)
							(mid -0.249642 0.249642)
							(end -0.1778 0.2794)
						)
						(arc
							(start 0.1778 0.2794)
							(mid 0.249642 0.249642)
							(end 0.2794 0.1778)
						)
						(arc
							(start 0.2794 -0.1778)
							(mid 0.249642 -0.249642)
							(end 0.1778 -0.2794)
						)
					)
					(width 0)
					(fill yes)
				)
			)
		)
		(pad "2" smd custom
			(at 0 0.4445 180)
			(size 0.1397 0.1397)
			(layers "F.Cu" "F.Mask" "F.Paste")
			(net "I2C_B_TMP3_A1")
			(options
				(clearance outline)
				(anchor circle)
			)
			(primitives
				(gr_poly
					(pts
						(arc
							(start -0.1778 -0.2794)
							(mid -0.249642 -0.249642)
							(end -0.2794 -0.1778)
						)
						(arc
							(start -0.2794 0.1778)
							(mid -0.249642 0.249642)
							(end -0.1778 0.2794)
						)
						(arc
							(start 0.1778 0.2794)
							(mid 0.249642 0.249642)
							(end 0.2794 0.1778)
						)
						(arc
							(start 0.2794 -0.1778)
							(mid 0.249642 -0.249642)
							(end 0.1778 -0.2794)
						)
					)
					(width 0)
					(fill yes)
				)
			)
		)
	)
	(footprint ""
		(layer "F.Cu")
		(at 218.142058 -366.851184 -90)
		(property "Reference" "C119"
			(at 0 0 270)
			(layer "F.SilkS")
			(hide yes)
			(effects
				(font
					(size 1.27 1.27)
				)
			)
		)
		(property "Value" "SCD01U50V2KX-1GP"
			(at 1.1811 -2.7051 270)
			(unlocked yes)
			(layer "F.Fab")
			(hide yes)
			(effects
				(font
					(size 1.016 1.016)
					(thickness 0.1524)
				)
			)
		)
		(property "Device Type" "C402H22"
			(at 1.1811 -4.2291 270)
			(unlocked yes)
			(layer "F.Fab")
			(hide yes)
			(effects
				(font
					(size 1.016 1.016)
					(thickness 0.1524)
				)
			)
		)
		(duplicate_pad_numbers_are_jumpers no)
		(fp_rect
			(start -0.4318 0.9525)
			(end 0.4318 -0.9525)
			(stroke
				(width 0)
				(type default)
			)
			(fill no)
			(layer "F.CrtYd")
		)
		(fp_rect
			(start -0.4318 0.9525)
			(end 0.4318 -0.9525)
			(stroke
				(width 0)
				(type default)
			)
			(fill no)
			(layer "F.Fab")
		)
		(pad "1" smd custom
			(at 0 -0.4445 270)
			(size 0.1524 0.1524)
			(layers "F.Cu" "F.Mask" "F.Paste")
			(net "SAS2X28_DRIVE_RX_P_A1")
			(options
				(clearance outline)
				(anchor circle)
			)
			(primitives
				(gr_poly
					(pts
						(arc
							(start 0.3048 -0.2032)
							(mid 0.275042 -0.275042)
							(end 0.2032 -0.3048)
						)
						(arc
							(start -0.2032 -0.3048)
							(mid -0.275042 -0.275042)
							(end -0.3048 -0.2032)
						)
						(arc
							(start -0.3048 0.2032)
							(mid -0.275042 0.275042)
							(end -0.2032 0.3048)
						)
						(arc
							(start 0.2032 0.3048)
							(mid 0.275042 0.275042)
							(end 0.3048 0.2032)
						)
					)
					(width 0)
					(fill yes)
				)
			)
		)
		(pad "2" smd custom
			(at 0 0.4445 270)
			(size 0.1524 0.1524)
			(layers "F.Cu" "F.Mask" "F.Paste")
			(net "SAS2X28_A_HDD1_RX_+")
			(options
				(clearance outline)
				(anchor circle)
			)
			(primitives
				(gr_poly
					(pts
						(arc
							(start 0.3048 -0.2032)
							(mid 0.275042 -0.275042)
							(end 0.2032 -0.3048)
						)
						(arc
							(start -0.2032 -0.3048)
							(mid -0.275042 -0.275042)
							(end -0.3048 -0.2032)
						)
						(arc
							(start -0.3048 0.2032)
							(mid -0.275042 0.275042)
							(end -0.2032 0.3048)
						)
						(arc
							(start 0.2032 0.3048)
							(mid 0.275042 0.275042)
							(end 0.3048 0.2032)
						)
					)
					(width 0)
					(fill yes)
				)
			)
		)
	)
	(footprint ""
		(layer "F.Cu")
		(at 73.242932 -496.145312)
		(property "Reference" "R443"
			(at 0 0 0)
			(layer "F.SilkS")
			(hide yes)
			(effects
				(font
					(size 1.27 1.27)
				)
			)
		)
		(property "Value" "4K7R2J-2-GP"
			(at 0.064008 -3.993896 0)
			(unlocked yes)
			(layer "F.Fab")
			(hide yes)
			(effects
				(font
					(size 1.016 1.016)
					(thickness 0.1524)
				)
			)
		)
		(property "Device Type" "R402H16"
			(at 0.064008 -5.517896 0)
			(unlocked yes)
			(layer "F.Fab")
			(hide yes)
			(effects
				(font
					(size 1.016 1.016)
					(thickness 0.1524)
				)
			)
		)
		(duplicate_pad_numbers_are_jumpers no)
		(fp_line
			(start -0.508 -0.9398)
			(end -0.508 0.9398)
			(stroke
				(width 0.1524)
				(type default)
			)
			(layer "F.SilkS")
		)
		(fp_line
			(start 0.508 -0.9398)
			(end -0.508 -0.9398)
			(stroke
				(width 0.1524)
				(type default)
			)
			(layer "F.SilkS")
		)
		(fp_rect
			(start -0.508 0.9398)
			(end 0.508 -0.9398)
			(stroke
				(width 0)
				(type default)
			)
			(fill no)
			(layer "F.CrtYd")
		)
		(fp_rect
			(start -0.508 0.9398)
			(end 0.508 -0.9398)
			(stroke
				(width 0)
				(type default)
			)
			(fill no)
			(layer "F.Fab")
		)
		(pad "1" smd custom
			(at 0 -0.4445)
			(size 0.1397 0.1397)
			(layers "F.Cu" "F.Mask" "F.Paste")
			(net "P3V3")
			(options
				(clearance outline)
				(anchor circle)
			)
			(primitives
				(gr_poly
					(pts
						(arc
							(start -0.1778 -0.2794)
							(mid -0.249642 -0.249642)
							(end -0.2794 -0.1778)
						)
						(arc
							(start -0.2794 0.1778)
							(mid -0.249642 0.249642)
							(end -0.1778 0.2794)
						)
						(arc
							(start 0.1778 0.2794)
							(mid 0.249642 0.249642)
							(end 0.2794 0.1778)
						)
						(arc
							(start 0.2794 -0.1778)
							(mid 0.249642 -0.249642)
							(end 0.1778 -0.2794)
						)
					)
					(width 0)
					(fill yes)
				)
			)
		)
		(pad "2" smd custom
			(at 0 0.4445)
			(size 0.1397 0.1397)
			(layers "F.Cu" "F.Mask" "F.Paste")
			(net "SAS2X28_B_HDD5_FLT")
			(options
				(clearance outline)
				(anchor circle)
			)
			(primitives
				(gr_poly
					(pts
						(arc
							(start -0.1778 -0.2794)
							(mid -0.249642 -0.249642)
							(end -0.2794 -0.1778)
						)
						(arc
							(start -0.2794 0.1778)
							(mid -0.249642 0.249642)
							(end -0.1778 0.2794)
						)
						(arc
							(start 0.1778 0.2794)
							(mid 0.249642 0.249642)
							(end 0.2794 0.1778)
						)
						(arc
							(start 0.2794 -0.1778)
							(mid 0.249642 -0.249642)
							(end 0.1778 -0.2794)
						)
					)
					(width 0)
					(fill yes)
				)
			)
		)
	)
	(footprint ""
		(layer "F.Cu")
		(at 21.226272 -500.446548 180)
		(property "Reference" "PC35"
			(at 0 0 180)
			(layer "F.SilkS")
			(hide yes)
			(effects
				(font
					(size 1.27 1.27)
				)
			)
		)
		(property "Value" "SC22U25V5MX-GP"
			(at -0.0762 -6.1214 180)
			(unlocked yes)
			(layer "F.Fab")
			(hide yes)
			(effects
				(font
					(size 1.016 1.016)
					(thickness 0.1524)
				)
			)
		)
		(property "Device Type" "C805H58"
			(at -0.0762 -8.1534 180)
			(unlocked yes)
			(layer "F.Fab")
			(hide yes)
			(effects
				(font
					(size 1.016 1.016)
					(thickness 0.1524)
				)
			)
		)
		(duplicate_pad_numbers_are_jumpers no)
		(fp_line
			(start 0.635 0)
			(end -0.635 0)
			(stroke
				(width 0.508)
				(type default)
			)
			(layer "F.SilkS")
		)
		(fp_rect
			(start -0.9652 1.778)
			(end 0.9652 -1.778)
			(stroke
				(width 0)
				(type default)
			)
			(fill no)
			(layer "F.CrtYd")
		)
		(fp_poly
			(pts
				(xy -0.9652 -1.778) (xy 0.9652 -1.778) (xy 0.9652 1.778) (xy -0.9652 1.778)
			)
			(stroke
				(width 0)
				(type default)
			)
			(fill no)
			(layer "F.Fab")
		)
		(pad "1" smd rect
			(at 0 -0.9652 180)
			(size 1.397 1.143)
			(layers "F.Cu" "F.Mask" "F.Paste")
			(net "P5VC_12VIN")
		)
		(pad "2" smd rect
			(at 0 0.9652 180)
			(size 1.397 1.143)
			(layers "F.Cu" "F.Mask" "F.Paste")
			(net "GND")
		)
	)
	(footprint ""
		(layer "F.Cu")
		(at 71.754746 -187.2107)
		(property "Reference" "U25"
			(at 0 0 0)
			(layer "F.SilkS")
			(hide yes)
			(effects
				(font
					(size 1.27 1.27)
				)
			)
		)
		(property "Value" "74LVC1G08GW-1-GP"
			(at -2.3368 -8.6868 0)
			(unlocked yes)
			(layer "F.Fab")
			(hide yes)
			(effects
				(font
					(size 1.016 1.016)
					(thickness 0.1524)
				)
			)
		)
		(property "Device Type" "SC70-5H44"
			(at -2.3114 -10.414 0)
			(unlocked yes)
			(layer "F.Fab")
			(hide yes)
			(effects
				(font
					(size 1.016 1.016)
					(thickness 0.1524)
				)
			)
		)
		(duplicate_pad_numbers_are_jumpers no)
		(fp_line
			(start -1.27 -1.7018)
			(end 1.27 -1.7018)
			(stroke
				(width 0.1524)
				(type default)
			)
			(layer "F.SilkS")
		)
		(fp_line
			(start -1.27 1.7018)
			(end -1.27 -1.7018)
			(stroke
				(width 0.1524)
				(type default)
			)
			(layer "F.SilkS")
		)
		(fp_line
			(start 0.6604 -1.8034)
			(end 1.3843 -1.8034)
			(stroke
				(width 0.3302)
				(type default)
			)
			(layer "F.SilkS")
		)
		(fp_line
			(start 1.27 -1.7018)
			(end 1.27 1.7018)
			(stroke
				(width 0.1524)
				(type default)
			)
			(layer "F.SilkS")
		)
		(fp_line
			(start 1.27 1.7018)
			(end -1.27 1.7018)
			(stroke
				(width 0.1524)
				(type default)
			)
			(layer "F.SilkS")
		)
		(fp_line
			(start 1.3843 -1.8034)
			(end 1.3843 -1.1176)
			(stroke
				(width 0.3302)
				(type default)
			)
			(layer "F.SilkS")
		)
		(fp_rect
			(start -1.524 1.9558)
			(end 1.524 -1.9558)
			(stroke
				(width 0)
				(type default)
			)
			(fill no)
			(layer "F.CrtYd")
		)
		(fp_poly
			(pts
				(xy -1.524 -1.9558) (xy 1.524 -1.9558) (xy 1.524 1.9558) (xy -1.524 1.9558)
			)
			(stroke
				(width 0)
				(type default)
			)
			(fill no)
			(layer "F.Fab")
		)
		(pad "1" smd rect
			(at 0.65024 -0.8255)
			(size 0.4064 1.2192)
			(layers "F.Cu" "F.Mask" "F.Paste")
			(net "SAS2X28_B_HDD8_FLT")
		)
		(pad "2" smd rect
			(at 0 -0.8255)
			(size 0.4064 1.2192)
			(layers "F.Cu" "F.Mask" "F.Paste")
			(net "SAS2X28_A_HDD8_FLT")
		)
		(pad "3" smd rect
			(at -0.65024 -0.8255)
			(size 0.4064 1.2192)
			(layers "F.Cu" "F.Mask" "F.Paste")
			(net "GND")
		)
		(pad "4" smd rect
			(at -0.65024 0.8255)
			(size 0.4064 1.2192)
			(layers "F.Cu" "F.Mask" "F.Paste")
			(net "FLT_HDD8_DRIVE")
		)
		(pad "5" smd rect
			(at 0.65024 0.8255)
			(size 0.4064 1.2192)
			(layers "F.Cu" "F.Mask" "F.Paste")
			(net "P3V3")
		)
	)
)
